FILE_TYPE = CONNECTIVITY;
{Allegro Design Entry HDL 17.2-2016 S081 (4005846) 1/11/2022}
"PAGE_NUMBER" = 88;
0"NC";
1"M_D_CPU0_SA_CB<7:0>";
2"M_D_CPU0_SA_CA<6:0>";
3"M_D_CPU0_SB_CA<6:0>";
4"M_D_CPU0_SB_CB<7:0>";
5"M_D_CPU0_SA_DQ<31:0>";
6"M_D_CPU0_SB_DQ<31:0>";
7"M_D_CPU0_SA_DQS_DP<9:0>";
8"M_D_CPU0_SB_DQS_DN<9:0>";
9"M_D_CPU0_SB_DQS_DP<9:0>";
10"M_D_CPU0_SA_DQS_DN<9:0>";
11"GND\g";
12"GND\g";
13"P3V3_STBY\g";
14"I3C_SPD_DDRAF_CPU0_SCL";
15"I3C_SPD_DDRD_CPU0_SCL";
16"PWRGD_CHD_CPU0_DIMM";
17"I3C_SPD_DDRAF_CPU0_SDA";
18"PD_CHD_CPU0_DIMM_SAA";
19"P3V3_STBY\g";
20"TP_CHD_CPU0_DIMM_RFU_6";
21"M_D_CPU0_SA_DQ<29>";
22"M_D_CPU0_SA_DQ<12>";
23"M_D_CPU0_SA_DQ<9>";
24"M_D_CPU0_SA_DQ<8>";
25"M_D_CPU0_SA_DQ<7>";
26"M_D_CPU0_SA_DQ<6>";
27"GND\g";
28"GND\g";
29"GND\g";
30"P12V_MEM_1\g";
31"M_D_CPU0_SA_DQS_DN<9>";
32"M_D_CPU0_SB_DQS_DP<8>";
33"M_D_CPU0_SB_DQS_DN<9>";
34"M_D_CPU0_SB_DQS_DP<9>";
35"M_D_CPU0_SA_DQS_DN<0>";
36"M_D_CPU0_SA_DQS_DN<1>";
37"M_D_CPU0_SA_DQS_DP<1>";
38"M_D_CPU0_SA_DQS_DP<9>";
39"M_D_CPU0_SA_DQS_DP<8>";
40"M_D_CPU0_SA_DQS_DN<8>";
41"M_D_CPU0_SB_DQS_DN<7>";
42"M_D_CPU0_SA_DQS_DP<7>";
43"M_D_CPU0_SB_DQS_DP<6>";
44"M_D_CPU0_SB_DQS_DN<6>";
45"M_D_CPU0_SA_DQS_DN<6>";
46"M_D_CPU0_SB_DQS_DP<5>";
47"M_D_CPU0_SB_DQS_DN<5>";
48"M_D_CPU0_SA_DQS_DP<5>";
49"M_D_CPU0_SA_DQS_DN<5>";
50"M_D_CPU0_SB_DQS_DP<4>";
51"M_D_CPU0_SB_DQS_DN<4>";
52"M_D_CPU0_SA_DQS_DP<4>";
53"M_D_CPU0_SA_DQS_DN<4>";
54"M_D_CPU0_SB_DQS_DP<3>";
55"M_D_CPU0_SB_DQS_DN<3>";
56"M_D_CPU0_SA_DQS_DP<3>";
57"M_D_CPU0_SA_DQS_DN<3>";
58"M_D_CPU0_SB_DQS_DP<2>";
59"M_D_CPU0_SB_DQS_DN<2>";
60"M_D_CPU0_SA_DQS_DP<2>";
61"M_D_CPU0_SA_DQS_DN<2>";
62"M_D_CPU0_SB_DQS_DP<1>";
63"M_D_CPU0_SB_DQS_DN<1>";
64"M_D_CPU0_SB_DQS_DP<0>";
65"M_D_CPU0_SB_DQS_DN<0>";
66"M_D_CPU0_SA_DQS_DP<0>";
67"M_D_CPU0_SB_DQS_DP<7>";
68"M_D_CPU0_SB_DQS_DN<8>";
69"M_D_CPU0_SA_DQS_DP<6>";
70"M_D_CPU0_SA_DQS_DN<7>";
71"M_D_CPU0_SA_CA<6>";
72"M_D_CPU0_SA_DQ<31>";
73"M_D_CPU0_SA_DQ<26>";
74"TP_CHD_CPU0_DIMM_RFU_0";
75"TP_CHD_CPU0_DIMM_RFU_1";
76"TP_CHD_CPU0_DIMM_RFU_2";
77"TP_CHD_CPU0_DIMM_RFU_3";
78"TP_CHD_CPU0_DIMM_RFU_4";
79"TP_CHD_CPU0_DIMM_RFU_5";
80"M_D_CPU0_RESET_N";
81"M_D_CPU0_SB_PAR";
82"M_D_CPU0_SA_PAR";
83"M_D_CPU0_SB_RSP<0>";
84"M_D_CPU0_SA_RSP<0>";
85"M_D_CPU0_SB_DQ<0>";
86"M_D_CPU0_SB_DQ<1>";
87"M_D_CPU0_SB_DQ<2>";
88"M_D_CPU0_SB_DQ<3>";
89"M_D_CPU0_SB_DQ<4>";
90"M_D_CPU0_SB_DQ<5>";
91"M_D_CPU0_SB_DQ<6>";
92"M_D_CPU0_SB_DQ<7>";
93"M_D_CPU0_SB_DQ<8>";
94"M_D_CPU0_SB_DQ<9>";
95"M_D_CPU0_SB_DQ<10>";
96"M_D_CPU0_SB_DQ<11>";
97"M_D_CPU0_SB_DQ<12>";
98"M_D_CPU0_SB_DQ<13>";
99"M_D_CPU0_SB_DQ<14>";
100"M_D_CPU0_SB_DQ<15>";
101"M_D_CPU0_SB_DQ<16>";
102"M_D_CPU0_SB_DQ<17>";
103"M_D_CPU0_SB_DQ<18>";
104"M_D_CPU0_SB_DQ<19>";
105"M_D_CPU0_SB_DQ<20>";
106"M_D_CPU0_SB_DQ<21>";
107"M_D_CPU0_SB_DQ<22>";
108"M_D_CPU0_SB_DQ<23>";
109"M_D_CPU0_SB_DQ<24>";
110"M_D_CPU0_SB_DQ<25>";
111"M_D_CPU0_SB_DQ<26>";
112"M_D_CPU0_SB_DQ<27>";
113"M_D_CPU0_SB_DQ<28>";
114"M_D_CPU0_SB_DQ<29>";
115"M_D_CPU0_SB_DQ<30>";
116"M_D_CPU0_SB_DQ<31>";
117"M_D_CPU0_SA_DQ<0>";
118"M_D_CPU0_SA_DQ<1>";
119"M_D_CPU0_SA_DQ<2>";
120"M_D_CPU0_SA_DQ<3>";
121"M_D_CPU0_SA_DQ<4>";
122"M_D_CPU0_SA_DQ<5>";
123"M_D_CPU0_SA_DQ<10>";
124"M_D_CPU0_SA_DQ<11>";
125"M_D_CPU0_SA_DQ<13>";
126"M_D_CPU0_SA_DQ<14>";
127"M_D_CPU0_SA_DQ<15>";
128"M_D_CPU0_SA_DQ<16>";
129"M_D_CPU0_SA_DQ<17>";
130"M_D_CPU0_SA_DQ<18>";
131"M_D_CPU0_SA_DQ<19>";
132"M_D_CPU0_SA_DQ<20>";
133"M_D_CPU0_SA_DQ<21>";
134"M_D_CPU0_SA_DQ<22>";
135"M_D_CPU0_SA_DQ<23>";
136"M_D_CPU0_SA_DQ<24>";
137"M_D_CPU0_SA_DQ<25>";
138"M_D_CPU0_SA_DQ<27>";
139"M_D_CPU0_SA_DQ<28>";
140"M_D_CPU0_SA_DQ<30>";
141"M_D_CPU0_SB_CS_N<1>";
142"M_D_CPU0_SA_CS_N<1>";
143"M_D_CPU0_SB_CS_N<0>";
144"M_D_CPU0_SA_CS_N<0>";
145"M_D_CPU0_CLK_DP<0>";
146"M_D_CPU0_CLK_DN<0>";
147"M_D_CPU0_SB_CB<0>";
148"M_D_CPU0_SB_CB<1>";
149"M_D_CPU0_SB_CB<2>";
150"M_D_CPU0_SB_CB<3>";
151"M_D_CPU0_SB_CB<4>";
152"M_D_CPU0_SB_CB<5>";
153"M_D_CPU0_SB_CB<6>";
154"M_D_CPU0_SA_CB<0>";
155"M_D_CPU0_SA_CB<2>";
156"M_D_CPU0_SA_CB<3>";
157"M_D_CPU0_SA_CB<5>";
158"M_D_CPU0_SA_CB<6>";
159"M_D_CPU0_SB_CA<6>";
160"M_D_CPU0_SB_CA<5>";
161"M_D_CPU0_SA_CA<5>";
162"M_D_CPU0_SB_CA<4>";
163"M_D_CPU0_SA_CA<4>";
164"M_D_CPU0_SB_CA<3>";
165"M_D_CPU0_SA_CA<3>";
166"M_D_CPU0_SB_CA<2>";
167"M_D_CPU0_SA_CA<2>";
168"M_D_CPU0_SB_CA<1>";
169"M_D_CPU0_SA_CA<1>";
170"M_D_CPU0_SB_CA<0>";
171"M_D_CPU0_SA_CA<0>";
172"M_D_CPU0_ALERT_N";
173"M_D_CPU0_SB_CB<7>";
174"M_D_CPU0_SA_CB<1>";
175"M_D_CPU0_SA_CB<4>";
176"M_D_CPU0_SA_CB<7>";
177"PWRGD_CHAF_CPU0";
178"PD_CHD_CPU0_DIMM_SAA";
%"GND"
"1","(-2250,1950)","0","mstr_symbols","I150";
;
CDS_LIB"mstr_symbols"
SIZE"1B"
BODY_TYPE"PLUMBING"
VOLTAGE"0.0"
HDL_POWER"GND";
"A\NAC"27;
%"GND"
"1","(-450,1750)","0","mstr_symbols","I152";
;
CDS_LIB"mstr_symbols"
SIZE"1B"
BODY_TYPE"PLUMBING"
VOLTAGE"0.0"
HDL_POWER"GND";
"A\NAC"29;
%"VCC_CORE"
"1","(-8475,3625)","0","mstr_symbols","I175";
;
HDL_POWER"P3V3_STBY"
CDS_LIB"mstr_symbols"
VOLTAGE"3.3"
ROOM"PVCCINFAON_CPU0_CTRL";
"A"19;
%"TAP"
"1","(-7775,3350)","2","mstr_standard","I189";
;
CDS_LIB"mstr_standard"
BODY_TYPE"PLUMBING"
HDL_TAP"TRUE";
"B \NAC \NWC"4;
"S \NAC"
BN"0"147;
%"TAP"
"1","(-7775,3400)","2","mstr_standard","I190";
;
CDS_LIB"mstr_standard"
BODY_TYPE"PLUMBING"
HDL_TAP"TRUE";
"B \NAC \NWC"4;
"S \NAC"
BN"1"148;
%"TAP"
"1","(-7775,3500)","2","mstr_standard","I191";
;
CDS_LIB"mstr_standard"
BODY_TYPE"PLUMBING"
HDL_TAP"TRUE";
"B \NAC \NWC"4;
"S \NAC"
BN"3"150;
%"TAP"
"1","(-7775,3450)","2","mstr_standard","I192";
;
CDS_LIB"mstr_standard"
BODY_TYPE"PLUMBING"
HDL_TAP"TRUE";
"B \NAC \NWC"4;
"S \NAC"
BN"2"149;
%"TAP"
"1","(-7775,3550)","2","mstr_standard","I193";
;
CDS_LIB"mstr_standard"
BODY_TYPE"PLUMBING"
HDL_TAP"TRUE";
"B \NAC \NWC"4;
"S \NAC"
BN"4"151;
%"TAP"
"1","(-7775,3600)","2","mstr_standard","I194";
;
CDS_LIB"mstr_standard"
BODY_TYPE"PLUMBING"
HDL_TAP"TRUE";
"B \NAC \NWC"4;
"S \NAC"
BN"5"152;
%"TAP"
"1","(-7775,3650)","2","mstr_standard","I195";
;
CDS_LIB"mstr_standard"
BODY_TYPE"PLUMBING"
HDL_TAP"TRUE";
"B \NAC \NWC"4;
"S \NAC"
BN"6"153;
%"TAP"
"1","(-7775,3700)","2","mstr_standard","I196";
;
CDS_LIB"mstr_standard"
BODY_TYPE"PLUMBING"
HDL_TAP"TRUE";
"B \NAC \NWC"4;
"S \NAC"
BN"7"173;
%"TAP"
"1","(-7775,3800)","2","mstr_standard","I197";
;
CDS_LIB"mstr_standard"
BODY_TYPE"PLUMBING"
HDL_TAP"TRUE";
"B \NAC \NWC"1;
"S \NAC"
BN"0"154;
%"TAP"
"1","(-7775,3850)","2","mstr_standard","I198";
;
CDS_LIB"mstr_standard"
BODY_TYPE"PLUMBING"
HDL_TAP"TRUE";
"B \NAC \NWC"1;
"S \NAC"
BN"1"174;
%"TAP"
"1","(-7775,3950)","2","mstr_standard","I199";
;
CDS_LIB"mstr_standard"
BODY_TYPE"PLUMBING"
HDL_TAP"TRUE";
"B \NAC \NWC"1;
"S \NAC"
BN"3"156;
%"TAP"
"1","(-7775,3900)","2","mstr_standard","I200";
;
CDS_LIB"mstr_standard"
BODY_TYPE"PLUMBING"
HDL_TAP"TRUE";
"B \NAC \NWC"1;
"S \NAC"
BN"2"155;
%"TAP"
"1","(-7775,4000)","2","mstr_standard","I201";
;
CDS_LIB"mstr_standard"
BODY_TYPE"PLUMBING"
HDL_TAP"TRUE";
"B \NAC \NWC"1;
"S \NAC"
BN"4"175;
%"TAP"
"1","(-7775,4050)","2","mstr_standard","I202";
;
CDS_LIB"mstr_standard"
BODY_TYPE"PLUMBING"
HDL_TAP"TRUE";
"B \NAC \NWC"1;
"S \NAC"
BN"5"157;
%"TAP"
"1","(-7775,4100)","2","mstr_standard","I203";
;
CDS_LIB"mstr_standard"
BODY_TYPE"PLUMBING"
HDL_TAP"TRUE";
"B \NAC \NWC"1;
"S \NAC"
BN"6"158;
%"TAP"
"1","(-6075,2350)","0","mstr_standard","I204";
;
CDS_LIB"mstr_standard"
BODY_TYPE"PLUMBING"
HDL_TAP"TRUE";
"B \NAC \NWC"6;
"S \NAC"
BN"0"85;
%"TAP"
"1","(-6075,2400)","0","mstr_standard","I205";
;
CDS_LIB"mstr_standard"
BODY_TYPE"PLUMBING"
HDL_TAP"TRUE";
"B \NAC \NWC"6;
"S \NAC"
BN"1"86;
%"TAP"
"1","(-6075,2450)","0","mstr_standard","I206";
;
CDS_LIB"mstr_standard"
BODY_TYPE"PLUMBING"
HDL_TAP"TRUE";
"B \NAC \NWC"6;
"S \NAC"
BN"2"87;
%"TAP"
"1","(-6075,2500)","0","mstr_standard","I207";
;
CDS_LIB"mstr_standard"
BODY_TYPE"PLUMBING"
HDL_TAP"TRUE";
"B \NAC \NWC"6;
"S \NAC"
BN"3"88;
%"TAP"
"1","(-6075,2550)","0","mstr_standard","I208";
;
CDS_LIB"mstr_standard"
BODY_TYPE"PLUMBING"
HDL_TAP"TRUE";
"B \NAC \NWC"6;
"S \NAC"
BN"4"89;
%"TAP"
"1","(-6075,2600)","0","mstr_standard","I209";
;
CDS_LIB"mstr_standard"
BODY_TYPE"PLUMBING"
HDL_TAP"TRUE";
"B \NAC \NWC"6;
"S \NAC"
BN"5"90;
%"TAP"
"1","(-6075,2700)","0","mstr_standard","I210";
;
CDS_LIB"mstr_standard"
BODY_TYPE"PLUMBING"
HDL_TAP"TRUE";
"B \NAC \NWC"6;
"S \NAC"
BN"7"92;
%"TAP"
"1","(-6075,2650)","0","mstr_standard","I211";
;
CDS_LIB"mstr_standard"
BODY_TYPE"PLUMBING"
HDL_TAP"TRUE";
"B \NAC \NWC"6;
"S \NAC"
BN"6"91;
%"TAP"
"1","(-6075,2750)","0","mstr_standard","I212";
;
CDS_LIB"mstr_standard"
BODY_TYPE"PLUMBING"
HDL_TAP"TRUE";
"B \NAC \NWC"6;
"S \NAC"
BN"8"93;
%"TAP"
"1","(-6075,2800)","0","mstr_standard","I213";
;
CDS_LIB"mstr_standard"
BODY_TYPE"PLUMBING"
HDL_TAP"TRUE";
"B \NAC \NWC"6;
"S \NAC"
BN"9"94;
%"TAP"
"1","(-6075,2850)","0","mstr_standard","I214";
;
CDS_LIB"mstr_standard"
BODY_TYPE"PLUMBING"
HDL_TAP"TRUE";
"B \NAC \NWC"6;
"S \NAC"
BN"10"95;
%"TAP"
"1","(-6075,2950)","0","mstr_standard","I215";
;
CDS_LIB"mstr_standard"
BODY_TYPE"PLUMBING"
HDL_TAP"TRUE";
"B \NAC \NWC"6;
"S \NAC"
BN"12"97;
%"TAP"
"1","(-6075,2900)","0","mstr_standard","I216";
;
CDS_LIB"mstr_standard"
BODY_TYPE"PLUMBING"
HDL_TAP"TRUE";
"B \NAC \NWC"6;
"S \NAC"
BN"11"96;
%"TAP"
"1","(-6075,3100)","0","mstr_standard","I217";
;
CDS_LIB"mstr_standard"
BODY_TYPE"PLUMBING"
HDL_TAP"TRUE";
"B \NAC \NWC"6;
"S \NAC"
BN"15"100;
%"TAP"
"1","(-6075,3050)","0","mstr_standard","I218";
;
CDS_LIB"mstr_standard"
BODY_TYPE"PLUMBING"
HDL_TAP"TRUE";
"B \NAC \NWC"6;
"S \NAC"
BN"14"99;
%"TAP"
"1","(-6075,3000)","0","mstr_standard","I219";
;
CDS_LIB"mstr_standard"
BODY_TYPE"PLUMBING"
HDL_TAP"TRUE";
"B \NAC \NWC"6;
"S \NAC"
BN"13"98;
%"TAP"
"1","(-6075,3250)","0","mstr_standard","I220";
;
CDS_LIB"mstr_standard"
BODY_TYPE"PLUMBING"
HDL_TAP"TRUE";
"B \NAC \NWC"6;
"S \NAC"
BN"18"103;
%"TAP"
"1","(-6075,3200)","0","mstr_standard","I221";
;
CDS_LIB"mstr_standard"
BODY_TYPE"PLUMBING"
HDL_TAP"TRUE";
"B \NAC \NWC"6;
"S \NAC"
BN"17"102;
%"TAP"
"1","(-6075,3150)","0","mstr_standard","I222";
;
CDS_LIB"mstr_standard"
BODY_TYPE"PLUMBING"
HDL_TAP"TRUE";
"B \NAC \NWC"6;
"S \NAC"
BN"16"101;
%"TAP"
"1","(-6075,3350)","0","mstr_standard","I223";
;
CDS_LIB"mstr_standard"
BODY_TYPE"PLUMBING"
HDL_TAP"TRUE";
"B \NAC \NWC"6;
"S \NAC"
BN"20"105;
%"TAP"
"1","(-6075,3300)","0","mstr_standard","I224";
;
CDS_LIB"mstr_standard"
BODY_TYPE"PLUMBING"
HDL_TAP"TRUE";
"B \NAC \NWC"6;
"S \NAC"
BN"19"104;
%"TAP"
"1","(-6075,3400)","0","mstr_standard","I225";
;
CDS_LIB"mstr_standard"
BODY_TYPE"PLUMBING"
HDL_TAP"TRUE";
"B \NAC \NWC"6;
"S \NAC"
BN"21"106;
%"TAP"
"1","(-6075,3450)","0","mstr_standard","I226";
;
CDS_LIB"mstr_standard"
BODY_TYPE"PLUMBING"
HDL_TAP"TRUE";
"B \NAC \NWC"6;
"S \NAC"
BN"22"107;
%"TAP"
"1","(-6075,3500)","0","mstr_standard","I227";
;
CDS_LIB"mstr_standard"
BODY_TYPE"PLUMBING"
HDL_TAP"TRUE";
"B \NAC \NWC"6;
"S \NAC"
BN"23"108;
%"TAP"
"1","(-6075,3550)","0","mstr_standard","I228";
;
CDS_LIB"mstr_standard"
BODY_TYPE"PLUMBING"
HDL_TAP"TRUE";
"B \NAC \NWC"6;
"S \NAC"
BN"24"109;
%"TAP"
"1","(-6075,3600)","0","mstr_standard","I229";
;
CDS_LIB"mstr_standard"
BODY_TYPE"PLUMBING"
HDL_TAP"TRUE";
"B \NAC \NWC"6;
"S \NAC"
BN"25"110;
%"TAP"
"1","(-6075,3650)","0","mstr_standard","I230";
;
CDS_LIB"mstr_standard"
BODY_TYPE"PLUMBING"
HDL_TAP"TRUE";
"B \NAC \NWC"6;
"S \NAC"
BN"26"111;
%"TAP"
"1","(-6075,3700)","0","mstr_standard","I231";
;
CDS_LIB"mstr_standard"
BODY_TYPE"PLUMBING"
HDL_TAP"TRUE";
"B \NAC \NWC"6;
"S \NAC"
BN"27"112;
%"TAP"
"1","(-6075,3750)","0","mstr_standard","I232";
;
CDS_LIB"mstr_standard"
BODY_TYPE"PLUMBING"
HDL_TAP"TRUE";
"B \NAC \NWC"6;
"S \NAC"
BN"28"113;
%"TAP"
"1","(-6075,3800)","0","mstr_standard","I233";
;
CDS_LIB"mstr_standard"
BODY_TYPE"PLUMBING"
HDL_TAP"TRUE";
"B \NAC \NWC"6;
"S \NAC"
BN"29"114;
%"TAP"
"1","(-6075,3850)","0","mstr_standard","I234";
;
CDS_LIB"mstr_standard"
BODY_TYPE"PLUMBING"
HDL_TAP"TRUE";
"B \NAC \NWC"6;
"S \NAC"
BN"30"115;
%"TAP"
"1","(-6075,4000)","0","mstr_standard","I235";
;
CDS_LIB"mstr_standard"
BODY_TYPE"PLUMBING"
HDL_TAP"TRUE";
"B \NAC \NWC"5;
"S \NAC"
BN"0"117;
%"TAP"
"1","(-6075,3900)","0","mstr_standard","I236";
;
CDS_LIB"mstr_standard"
BODY_TYPE"PLUMBING"
HDL_TAP"TRUE";
"B \NAC \NWC"6;
"S \NAC"
BN"31"116;
%"TAP"
"1","(-6075,4050)","0","mstr_standard","I237";
;
CDS_LIB"mstr_standard"
BODY_TYPE"PLUMBING"
HDL_TAP"TRUE";
"B \NAC \NWC"5;
"S \NAC"
BN"1"118;
%"TAP"
"1","(-6075,4100)","0","mstr_standard","I238";
;
CDS_LIB"mstr_standard"
BODY_TYPE"PLUMBING"
HDL_TAP"TRUE";
"B \NAC \NWC"5;
"S \NAC"
BN"2"119;
%"TAP"
"1","(-7775,4150)","2","mstr_standard","I239";
;
CDS_LIB"mstr_standard"
BODY_TYPE"PLUMBING"
HDL_TAP"TRUE";
"B \NAC \NWC"1;
"S \NAC"
BN"7"176;
%"TAP"
"1","(-7775,4850)","2","mstr_standard","I240";
;
CDS_LIB"mstr_standard"
BODY_TYPE"PLUMBING"
HDL_TAP"TRUE";
"B \NAC \NWC"3;
"S \NAC"
BN"0"170;
%"TAP"
"1","(-7775,4900)","2","mstr_standard","I241";
;
CDS_LIB"mstr_standard"
BODY_TYPE"PLUMBING"
HDL_TAP"TRUE";
"B \NAC \NWC"3;
"S \NAC"
BN"1"168;
%"TAP"
"1","(-7775,4950)","2","mstr_standard","I242";
;
CDS_LIB"mstr_standard"
BODY_TYPE"PLUMBING"
HDL_TAP"TRUE";
"B \NAC \NWC"3;
"S \NAC"
BN"2"166;
%"TAP"
"1","(-7775,5000)","2","mstr_standard","I243";
;
CDS_LIB"mstr_standard"
BODY_TYPE"PLUMBING"
HDL_TAP"TRUE";
"B \NAC \NWC"3;
"S \NAC"
BN"3"164;
%"TAP"
"1","(-7775,5050)","2","mstr_standard","I244";
;
CDS_LIB"mstr_standard"
BODY_TYPE"PLUMBING"
HDL_TAP"TRUE";
"B \NAC \NWC"3;
"S \NAC"
BN"4"162;
%"TAP"
"1","(-7775,5100)","2","mstr_standard","I245";
;
CDS_LIB"mstr_standard"
BODY_TYPE"PLUMBING"
HDL_TAP"TRUE";
"B \NAC \NWC"3;
"S \NAC"
BN"5"160;
%"TAP"
"1","(-7775,5150)","2","mstr_standard","I246";
;
CDS_LIB"mstr_standard"
BODY_TYPE"PLUMBING"
HDL_TAP"TRUE";
"B \NAC \NWC"3;
"S \NAC"
BN"6"159;
%"TAP"
"1","(-7775,5250)","2","mstr_standard","I247";
;
CDS_LIB"mstr_standard"
BODY_TYPE"PLUMBING"
HDL_TAP"TRUE";
"B \NAC \NWC"2;
"S \NAC"
BN"0"171;
%"TAP"
"1","(-7775,5300)","2","mstr_standard","I248";
;
CDS_LIB"mstr_standard"
BODY_TYPE"PLUMBING"
HDL_TAP"TRUE";
"B \NAC \NWC"2;
"S \NAC"
BN"1"169;
%"TAP"
"1","(-7775,5350)","2","mstr_standard","I249";
;
CDS_LIB"mstr_standard"
BODY_TYPE"PLUMBING"
HDL_TAP"TRUE";
"B \NAC \NWC"2;
"S \NAC"
BN"2"167;
%"TAP"
"1","(-7775,5400)","2","mstr_standard","I250";
;
CDS_LIB"mstr_standard"
BODY_TYPE"PLUMBING"
HDL_TAP"TRUE";
"B \NAC \NWC"2;
"S \NAC"
BN"3"165;
%"TAP"
"1","(-7775,5450)","2","mstr_standard","I251";
;
CDS_LIB"mstr_standard"
BODY_TYPE"PLUMBING"
HDL_TAP"TRUE";
"B \NAC \NWC"2;
"S \NAC"
BN"4"163;
%"TAP"
"1","(-7775,5500)","2","mstr_standard","I252";
;
CDS_LIB"mstr_standard"
BODY_TYPE"PLUMBING"
HDL_TAP"TRUE";
"B \NAC \NWC"2;
"S \NAC"
BN"5"161;
%"TAP"
"1","(-7775,5550)","2","mstr_standard","I253";
;
CDS_LIB"mstr_standard"
BODY_TYPE"PLUMBING"
HDL_TAP"TRUE";
"B \NAC \NWC"2;
"S \NAC"
BN"6"71;
%"TAP"
"1","(-6075,4150)","0","mstr_standard","I254";
;
CDS_LIB"mstr_standard"
BODY_TYPE"PLUMBING"
HDL_TAP"TRUE";
"B \NAC \NWC"5;
"S \NAC"
BN"3"120;
%"TAP"
"1","(-6075,4200)","0","mstr_standard","I255";
;
CDS_LIB"mstr_standard"
BODY_TYPE"PLUMBING"
HDL_TAP"TRUE";
"B \NAC \NWC"5;
"S \NAC"
BN"4"121;
%"TAP"
"1","(-6075,4250)","0","mstr_standard","I256";
;
CDS_LIB"mstr_standard"
BODY_TYPE"PLUMBING"
HDL_TAP"TRUE";
"B \NAC \NWC"5;
"S \NAC"
BN"5"122;
%"TAP"
"1","(-6075,4350)","0","mstr_standard","I257";
;
CDS_LIB"mstr_standard"
BODY_TYPE"PLUMBING"
HDL_TAP"TRUE";
"B \NAC \NWC"5;
"S \NAC"
BN"7"25;
%"TAP"
"1","(-6075,4300)","0","mstr_standard","I258";
;
CDS_LIB"mstr_standard"
BODY_TYPE"PLUMBING"
HDL_TAP"TRUE";
"B \NAC \NWC"5;
"S \NAC"
BN"6"26;
%"TAP"
"1","(-6075,4400)","0","mstr_standard","I259";
;
CDS_LIB"mstr_standard"
BODY_TYPE"PLUMBING"
HDL_TAP"TRUE";
"B \NAC \NWC"5;
"S \NAC"
BN"8"24;
%"TAP"
"1","(-6075,4450)","0","mstr_standard","I260";
;
CDS_LIB"mstr_standard"
BODY_TYPE"PLUMBING"
HDL_TAP"TRUE";
"B \NAC \NWC"5;
"S \NAC"
BN"9"23;
%"TAP"
"1","(-6075,4500)","0","mstr_standard","I261";
;
CDS_LIB"mstr_standard"
BODY_TYPE"PLUMBING"
HDL_TAP"TRUE";
"B \NAC \NWC"5;
"S \NAC"
BN"10"123;
%"TAP"
"1","(-6075,4550)","0","mstr_standard","I262";
;
CDS_LIB"mstr_standard"
BODY_TYPE"PLUMBING"
HDL_TAP"TRUE";
"B \NAC \NWC"5;
"S \NAC"
BN"11"124;
%"TAP"
"1","(-6075,4600)","0","mstr_standard","I263";
;
CDS_LIB"mstr_standard"
BODY_TYPE"PLUMBING"
HDL_TAP"TRUE";
"B \NAC \NWC"5;
"S \NAC"
BN"12"22;
%"TAP"
"1","(-6075,4650)","0","mstr_standard","I264";
;
CDS_LIB"mstr_standard"
BODY_TYPE"PLUMBING"
HDL_TAP"TRUE";
"B \NAC \NWC"5;
"S \NAC"
BN"13"125;
%"TAP"
"1","(-6075,4700)","0","mstr_standard","I265";
;
CDS_LIB"mstr_standard"
BODY_TYPE"PLUMBING"
HDL_TAP"TRUE";
"B \NAC \NWC"5;
"S \NAC"
BN"14"126;
%"TAP"
"1","(-6075,4750)","0","mstr_standard","I266";
;
CDS_LIB"mstr_standard"
BODY_TYPE"PLUMBING"
HDL_TAP"TRUE";
"B \NAC \NWC"5;
"S \NAC"
BN"15"127;
%"TAP"
"1","(-6075,4850)","0","mstr_standard","I267";
;
CDS_LIB"mstr_standard"
BODY_TYPE"PLUMBING"
HDL_TAP"TRUE";
"B \NAC \NWC"5;
"S \NAC"
BN"17"129;
%"TAP"
"1","(-6075,4900)","0","mstr_standard","I268";
;
CDS_LIB"mstr_standard"
BODY_TYPE"PLUMBING"
HDL_TAP"TRUE";
"B \NAC \NWC"5;
"S \NAC"
BN"18"130;
%"TAP"
"1","(-6075,4800)","0","mstr_standard","I269";
;
CDS_LIB"mstr_standard"
BODY_TYPE"PLUMBING"
HDL_TAP"TRUE";
"B \NAC \NWC"5;
"S \NAC"
BN"16"128;
%"TAP"
"1","(-6075,4950)","0","mstr_standard","I270";
;
CDS_LIB"mstr_standard"
BODY_TYPE"PLUMBING"
HDL_TAP"TRUE";
"B \NAC \NWC"5;
"S \NAC"
BN"19"131;
%"TAP"
"1","(-6075,5000)","0","mstr_standard","I271";
;
CDS_LIB"mstr_standard"
BODY_TYPE"PLUMBING"
HDL_TAP"TRUE";
"B \NAC \NWC"5;
"S \NAC"
BN"20"132;
%"TAP"
"1","(-6075,5100)","0","mstr_standard","I272";
;
CDS_LIB"mstr_standard"
BODY_TYPE"PLUMBING"
HDL_TAP"TRUE";
"B \NAC \NWC"5;
"S \NAC"
BN"22"134;
%"TAP"
"1","(-6075,5050)","0","mstr_standard","I273";
;
CDS_LIB"mstr_standard"
BODY_TYPE"PLUMBING"
HDL_TAP"TRUE";
"B \NAC \NWC"5;
"S \NAC"
BN"21"133;
%"TAP"
"1","(-6075,5150)","0","mstr_standard","I274";
;
CDS_LIB"mstr_standard"
BODY_TYPE"PLUMBING"
HDL_TAP"TRUE";
"B \NAC \NWC"5;
"S \NAC"
BN"23"135;
%"TAP"
"1","(-6075,5200)","0","mstr_standard","I275";
;
CDS_LIB"mstr_standard"
BODY_TYPE"PLUMBING"
HDL_TAP"TRUE";
"B \NAC \NWC"5;
"S \NAC"
BN"24"136;
%"TAP"
"1","(-6075,5250)","0","mstr_standard","I276";
;
CDS_LIB"mstr_standard"
BODY_TYPE"PLUMBING"
HDL_TAP"TRUE";
"B \NAC \NWC"5;
"S \NAC"
BN"25"137;
%"TAP"
"1","(-6075,5300)","0","mstr_standard","I277";
;
CDS_LIB"mstr_standard"
BODY_TYPE"PLUMBING"
HDL_TAP"TRUE";
"B \NAC \NWC"5;
"S \NAC"
BN"26"73;
%"TAP"
"1","(-6075,5350)","0","mstr_standard","I278";
;
CDS_LIB"mstr_standard"
BODY_TYPE"PLUMBING"
HDL_TAP"TRUE";
"B \NAC \NWC"5;
"S \NAC"
BN"27"138;
%"TAP"
"1","(-6075,5400)","0","mstr_standard","I279";
;
CDS_LIB"mstr_standard"
BODY_TYPE"PLUMBING"
HDL_TAP"TRUE";
"B \NAC \NWC"5;
"S \NAC"
BN"28"139;
%"TAP"
"1","(-6075,5450)","0","mstr_standard","I280";
;
CDS_LIB"mstr_standard"
BODY_TYPE"PLUMBING"
HDL_TAP"TRUE";
"B \NAC \NWC"5;
"S \NAC"
BN"29"21;
%"TAP"
"1","(-6075,5500)","0","mstr_standard","I281";
;
CDS_LIB"mstr_standard"
BODY_TYPE"PLUMBING"
HDL_TAP"TRUE";
"B \NAC \NWC"5;
"S \NAC"
BN"30"140;
%"TAP"
"1","(-6075,5550)","0","mstr_standard","I282";
;
CDS_LIB"mstr_standard"
BODY_TYPE"PLUMBING"
HDL_TAP"TRUE";
"B \NAC \NWC"5;
"S \NAC"
BN"31"72;
%"GND"
"1","(-6450,1175)","0","mstr_symbols","I332";
;
SIZE"1B"
CDS_LIB"mstr_symbols"
BOM_COST"MEM"
BODY_TYPE"PLUMBING"
VOLTAGE"0.0"
HDL_POWER"GND";
"A\NAC"11;
%"Q_RES"
"2","(-6450,1425)","0","pure_quanta","I349";
;
LOCATION"R763"
$SEC"1"
CDS_SEC"1"
WATTAGE"1/16W"
MATERIAL"CHIP"
TOLERANCE"1%"
VALUE"35.7K"
PART_NUMBER"CS33572FB01"
PACK_TYPE"0402LF"
CDS_LIB"pure_quanta";
"A"
$PN"1"178;
"B"
$PN"2"11;
%"SCONN288_DDR506112002KQ"
"1","(-6925,3800)","0","pure_quanta","I350";
;
LOCATION"J19"
$SEC"1"
CDS_SEC"1"
PART_TYPE"SMLF"
MATERIAL"IO"
VALUE"SCONN288_DDR506112002KQ"
PART_NUMBER"DFHST8FS479"
CDS_LMAN_SYM_OUTLINE"-450,1900,450,-1850"
NEEDS_NO_SIZE"TRUE"
CDS_LIB"pure_quanta";
"PWR_GOOD||FAIL_N"
$PN"147"16;
"DQ31_A"
$PN"194"72;
"CB7_A"
$PN"205"176;
"CB4_A"
$PN"58"175;
"CB1_A"
$PN"53"174;
"CB7_B"
$PN"236"173;
"ALERT_N \B"
$PN"62"172;
"CA0_A"
$PN"66"171;
"CA0_B"
$PN"76"170;
"CA1_A"
$PN"211"169;
"CA1_B"
$PN"221"168;
"CA2_A"
$PN"68"167;
"CA2_B"
$PN"78"166;
"CA3_A"
$PN"213"165;
"CA3_B"
$PN"223"164;
"CA4_A"
$PN"70"163;
"CA4_B"
$PN"80"162;
"CA5_A"
$PN"215"161;
"CA5_B"
$PN"225"160;
"CA6_A"
$PN"72"71;
"CA6_B"
$PN"82"159;
"CB6_A"
$PN"203"158;
"CB5_A"
$PN"60"157;
"CB3_A"
$PN"198"156;
"CB2_A"
$PN"196"155;
"CB0_A"
$PN"51"154;
"CB6_B"
$PN"234"153;
"CB5_B"
$PN"91"152;
"CB4_B"
$PN"89"151;
"CB3_B"
$PN"243"150;
"CB2_B"
$PN"241"149;
"CB1_B"
$PN"98"148;
"CB0_B"
$PN"96"147;
"CK_C \B"
$PN"218"146;
"CK_T"
$PN"217"145;
"CS0_A_N"
$PN"64"144;
"CS0_B_N"
$PN"84"143;
"CS1_A_N"
$PN"209"142;
"CS1_B_N"
$PN"229"141;
"DQ30_A"
$PN"192"140;
"DQ29_A"
$PN"49"21;
"DQ28_A"
$PN"47"139;
"DQ27_A"
$PN"187"138;
"DQ26_A"
$PN"185"73;
"DQ25_A"
$PN"42"137;
"DQ24_A"
$PN"40"136;
"DQ23_A"
$PN"183"135;
"DQ22_A"
$PN"181"134;
"DQ21_A"
$PN"38"133;
"DQ20_A"
$PN"36"132;
"DQ19_A"
$PN"176"131;
"DQ18_A"
$PN"174"130;
"DQ17_A"
$PN"31"129;
"DQ16_A"
$PN"29"128;
"DQ15_A"
$PN"172"127;
"DQ14_A"
$PN"170"126;
"DQ13_A"
$PN"27"125;
"DQ12_A"
$PN"25"22;
"DQ11_A"
$PN"165"124;
"DQ10_A"
$PN"163"123;
"DQ9_A"
$PN"20"23;
"DQ8_A"
$PN"18"24;
"DQ7_A"
$PN"161"25;
"DQ6_A"
$PN"159"26;
"DQ5_A"
$PN"16"122;
"DQ4_A"
$PN"14"121;
"DQ3_A"
$PN"154"120;
"DQ2_A"
$PN"152"119;
"DQ1_A"
$PN"9"118;
"DQ0_A"
$PN"7"117;
"DQ31_B"
$PN"287"116;
"DQ30_B"
$PN"285"115;
"DQ29_B"
$PN"142"114;
"DQ28_B"
$PN"140"113;
"DQ27_B"
$PN"280"112;
"DQ26_B"
$PN"278"111;
"DQ25_B"
$PN"135"110;
"DQ24_B"
$PN"133"109;
"DQ23_B"
$PN"276"108;
"DQ22_B"
$PN"274"107;
"DQ21_B"
$PN"131"106;
"DQ20_B"
$PN"129"105;
"DQ19_B"
$PN"269"104;
"DQ18_B"
$PN"267"103;
"DQ17_B"
$PN"124"102;
"DQ16_B"
$PN"122"101;
"DQ15_B"
$PN"265"100;
"DQ14_B"
$PN"263"99;
"DQ13_B"
$PN"120"98;
"DQ12_B"
$PN"118"97;
"DQ11_B"
$PN"258"96;
"DQ10_B"
$PN"256"95;
"DQ9_B"
$PN"113"94;
"DQ8_B"
$PN"111"93;
"DQ7_B"
$PN"254"92;
"DQ6_B"
$PN"252"91;
"DQ5_B"
$PN"109"90;
"DQ4_B"
$PN"107"89;
"DQ3_B"
$PN"247"88;
"DQ2_B"
$PN"245"87;
"DQ1_B"
$PN"102"86;
"DQ0_B"
$PN"100"85;
"HAS"
$PN"148"18;
"HSCL"
$PN"4"15;
"HSDA"
$PN"5"17;
"LBD||RSP_A_N"
$PN"86"84;
"LBS||RSP_B_N"
$PN"87"83;
"PAR_A"
$PN"74"82;
"PAR_B"
$PN"227"81;
"RESET_N \B"
$PN"207"80;
"RFU6"
$PN"232"20;
"RFU5"
$PN"231"79;
"RFU4"
$PN"220"78;
"RFU3"
$PN"150"77;
"RFU2"
$PN"149"76;
"RFU1"
$PN"144"75;
"RFU0"
$PN"2"74;
"VIN_MGMT"
$PN"3"19;
%"SCONN288_DDR506112002KQ"
"3","(-1350,3700)","0","pure_quanta","I352";
;
LOCATION"J19"
$SEC"3"
CDS_SEC"3"
VALUE"SCONN288_DDR506112002KQ"
PART_TYPE"SMLF"
MATERIAL"IO"
PART_NUMBER"DFHST8FS479"
CDS_LMAN_SYM_OUTLINE"-450,1800,450,-1750"
NEEDS_NO_SIZE"TRUE"
CDS_LIB"pure_quanta";
"G3"
$PN"G3"29;
"G2"
$PN"G2"29;
"G1"
$PN"G1"29;
"VSS62"
$PN"141"29;
"VSS61"
$PN"139"29;
"VSS60"
$PN"136"29;
"VSS58"
$PN"132"29;
"VSS104"
$PN"240"27;
"VSS102"
$PN"235"27;
"VSS100"
$PN"230"27;
"VIN_BULK2"
$PN"146"30;
"VIN_BULK1"
$PN"145"30;
"VIN_BULK0"
$PN"1"30;
"VSS126"
$PN"288"27;
"VSS125"
$PN"286"27;
"VSS124"
$PN"284"27;
"VSS123"
$PN"281"27;
"VSS122"
$PN"279"27;
"VSS121"
$PN"277"27;
"VSS120"
$PN"275"27;
"VSS119"
$PN"273"27;
"VSS118"
$PN"270"27;
"VSS117"
$PN"268"27;
"VSS116"
$PN"266"27;
"VSS115"
$PN"264"27;
"VSS114"
$PN"262"27;
"VSS113"
$PN"259"27;
"VSS112"
$PN"257"27;
"VSS111"
$PN"255"27;
"VSS110"
$PN"253"27;
"VSS109"
$PN"251"27;
"VSS108"
$PN"248"27;
"VSS107"
$PN"246"27;
"VSS106"
$PN"244"27;
"VSS105"
$PN"242"27;
"VSS103"
$PN"237"27;
"VSS101"
$PN"233"27;
"VSS99"
$PN"228"27;
"VSS98"
$PN"226"27;
"VSS97"
$PN"224"27;
"VSS96"
$PN"222"27;
"VSS95"
$PN"219"27;
"VSS94"
$PN"216"27;
"VSS93"
$PN"214"27;
"VSS92"
$PN"212"27;
"VSS91"
$PN"210"27;
"VSS90"
$PN"208"27;
"VSS89"
$PN"206"27;
"VSS88"
$PN"204"27;
"VSS87"
$PN"202"27;
"VSS86"
$PN"199"27;
"VSS85"
$PN"197"27;
"VSS84"
$PN"195"27;
"VSS83"
$PN"193"27;
"VSS82"
$PN"191"27;
"VSS81"
$PN"188"27;
"VSS80"
$PN"186"27;
"VSS79"
$PN"184"27;
"VSS78"
$PN"182"27;
"VSS77"
$PN"180"27;
"VSS76"
$PN"177"27;
"VSS75"
$PN"175"27;
"VSS74"
$PN"173"27;
"VSS73"
$PN"171"27;
"VSS72"
$PN"169"27;
"VSS71"
$PN"166"27;
"VSS70"
$PN"164"27;
"VSS69"
$PN"162"27;
"VSS68"
$PN"160"27;
"VSS67"
$PN"158"27;
"VSS66"
$PN"155"27;
"VSS65"
$PN"153"27;
"VSS64"
$PN"151"27;
"VSS63"
$PN"143"29;
"VSS59"
$PN"134"29;
"VSS57"
$PN"130"29;
"VSS56"
$PN"128"29;
"VSS55"
$PN"125"29;
"VSS54"
$PN"123"29;
"VSS53"
$PN"121"29;
"VSS52"
$PN"119"29;
"VSS51"
$PN"117"29;
"VSS50"
$PN"114"29;
"VSS49"
$PN"112"29;
"VSS48"
$PN"110"29;
"VSS47"
$PN"108"29;
"VSS46"
$PN"106"29;
"VSS45"
$PN"103"29;
"VSS44"
$PN"101"29;
"VSS43"
$PN"99"29;
"VSS42"
$PN"97"29;
"VSS41"
$PN"95"29;
"VSS40"
$PN"92"29;
"VSS39"
$PN"90"29;
"VSS38"
$PN"88"29;
"VSS37"
$PN"85"29;
"VSS36"
$PN"83"29;
"VSS35"
$PN"81"29;
"VSS34"
$PN"79"29;
"VSS33"
$PN"77"29;
"VSS32"
$PN"75"29;
"VSS31"
$PN"73"29;
"VSS30"
$PN"71"29;
"VSS29"
$PN"69"29;
"VSS28"
$PN"67"29;
"VSS27"
$PN"65"29;
"VSS26"
$PN"63"29;
"VSS25"
$PN"61"29;
"VSS24"
$PN"59"29;
"VSS23"
$PN"57"29;
"VSS22"
$PN"54"29;
"VSS21"
$PN"52"29;
"VSS20"
$PN"50"29;
"VSS19"
$PN"48"29;
"VSS18"
$PN"46"29;
"VSS17"
$PN"43"29;
"VSS16"
$PN"41"29;
"VSS15"
$PN"39"29;
"VSS14"
$PN"37"29;
"VSS13"
$PN"35"29;
"VSS12"
$PN"32"29;
"VSS11"
$PN"30"29;
"VSS10"
$PN"28"29;
"VSS9"
$PN"26"29;
"VSS8"
$PN"24"29;
"VSS7"
$PN"21"29;
"VSS6"
$PN"19"29;
"VSS5"
$PN"17"29;
"VSS4"
$PN"15"29;
"VSS3"
$PN"13"29;
"VSS2"
$PN"10"29;
"VSS1"
$PN"8"29;
"VSS0"
$PN"6"29;
%"GND"
"1","(-8600,3150)","0","mstr_symbols","I361";
;
BOM_COST"MEM"
SIZE"1B"
CDS_LIB"mstr_symbols"
BODY_TYPE"PLUMBING"
VOLTAGE"0"
ROOM"MEM_EFGH_DECOUPLING_CAPS"
HDL_POWER"GND";
"A\NAC"12;
%"Q_CAP"
"1","(-8600,3375)","2","pure_quanta","I362";
;
LOCATION"C100"
$SEC"1"
CDS_SEC"1"
MATERIAL"X7R"
TOLERANCE"10%"
VALUE"0.1UF"
VOLTAGE"25V"
PART_NUMBER"CH4104K1B00"
PACK_TYPE"0402"
BOM_COST"MEM"
CDS_LIB"pure_quanta"
ROOM"MEM_CH_A_CPU0_DIMM1";
"B"
$PN"2"12;
"A"
$PN"1"19;
%"Q_RES"
"2","(-8375,2450)","0","pure_quanta","I367";
;
LOCATION"R92"
$SEC"1"
CDS_SEC"1"
WATTAGE"1/16W"
MATERIAL"EMPTY"
TOLERANCE"5%"
VALUE"1K"
PACK_TYPE"0402LF"
BOM_COST"MEM"
CDS_LIB"pure_quanta"
PART_NUMBER"TMP_QCS21002JB34"
ROOM"MEM_CH_A_CPU0_DIMM1";
"A"
$PN"1"13;
"B"
$PN"2"16;
%"VCC_CORE"
"1","(-8375,2625)","0","mstr_symbols","I368";
;
HDL_POWER"P3V3_STBY"
CDS_LIB"mstr_symbols"
VOLTAGE"3.3"
ROOM"PVCCINFAON_CPU0_CTRL";
"A"13;
%"Q_RES"
"1","(-8500,2300)","2","pure_quanta","I369";
;
LOCATION"R294"
$SEC"1"
CDS_SEC"1"
VALUE"0"
BOM_COST"MEM"
CDS_LIB"pure_quanta"
WATTAGE"1/16W"
MATERIAL"CHIP"
TOLERANCE"5%"
PART_NUMBER"CS00002JB38"
PACK_TYPE"0402LF"
ROOM"RST_CPU0_PLD_TO_DIMM";
"B"
$PN"2"177;
"A"
$PN"1"16;
%"TAP"
"1","(-3500,4575)","0","mstr_standard","I375";
;
CDS_LIB"mstr_standard"
BODY_TYPE"PLUMBING"
HDL_TAP"TRUE";
"B \NAC \NWC"10;
"S \NAC"
BN"9"31;
%"TAP"
"1","(-3500,4475)","0","mstr_standard","I376";
;
CDS_LIB"mstr_standard"
BODY_TYPE"PLUMBING"
HDL_TAP"TRUE";
"B \NAC \NWC"10;
"S \NAC"
BN"8"40;
%"TAP"
"1","(-3500,4375)","0","mstr_standard","I377";
;
CDS_LIB"mstr_standard"
BODY_TYPE"PLUMBING"
HDL_TAP"TRUE";
"B \NAC \NWC"10;
"S \NAC"
BN"7"70;
%"TAP"
"1","(-3500,4275)","0","mstr_standard","I378";
;
CDS_LIB"mstr_standard"
BODY_TYPE"PLUMBING"
HDL_TAP"TRUE";
"B \NAC \NWC"10;
"S \NAC"
BN"6"45;
%"TAP"
"1","(-3700,4525)","0","mstr_standard","I379";
;
CDS_LIB"mstr_standard"
BODY_TYPE"PLUMBING"
HDL_TAP"TRUE";
"B \NAC \NWC"7;
"S \NAC"
BN"8"39;
%"TAP"
"1","(-3700,4625)","0","mstr_standard","I380";
;
CDS_LIB"mstr_standard"
BODY_TYPE"PLUMBING"
HDL_TAP"TRUE";
"B \NAC \NWC"7;
"S \NAC"
BN"9"38;
%"TAP"
"1","(-3700,4425)","0","mstr_standard","I381";
;
CDS_LIB"mstr_standard"
BODY_TYPE"PLUMBING"
HDL_TAP"TRUE";
"B \NAC \NWC"7;
"S \NAC"
BN"7"42;
%"TAP"
"1","(-3700,4325)","0","mstr_standard","I382";
;
CDS_LIB"mstr_standard"
BODY_TYPE"PLUMBING"
HDL_TAP"TRUE";
"B \NAC \NWC"7;
"S \NAC"
BN"6"69;
%"TAP"
"1","(-3500,4175)","0","mstr_standard","I383";
;
CDS_LIB"mstr_standard"
BODY_TYPE"PLUMBING"
HDL_TAP"TRUE";
"B \NAC \NWC"10;
"S \NAC"
BN"5"49;
%"TAP"
"1","(-3500,4075)","0","mstr_standard","I384";
;
CDS_LIB"mstr_standard"
BODY_TYPE"PLUMBING"
HDL_TAP"TRUE";
"B \NAC \NWC"10;
"S \NAC"
BN"4"53;
%"TAP"
"1","(-3500,3975)","0","mstr_standard","I385";
;
CDS_LIB"mstr_standard"
BODY_TYPE"PLUMBING"
HDL_TAP"TRUE";
"B \NAC \NWC"10;
"S \NAC"
BN"3"57;
%"TAP"
"1","(-3500,3875)","0","mstr_standard","I386";
;
CDS_LIB"mstr_standard"
BODY_TYPE"PLUMBING"
HDL_TAP"TRUE";
"B \NAC \NWC"10;
"S \NAC"
BN"2"61;
%"TAP"
"1","(-3500,3775)","0","mstr_standard","I387";
;
CDS_LIB"mstr_standard"
BODY_TYPE"PLUMBING"
HDL_TAP"TRUE";
"B \NAC \NWC"10;
"S \NAC"
BN"1"36;
%"TAP"
"1","(-3700,4225)","0","mstr_standard","I388";
;
CDS_LIB"mstr_standard"
BODY_TYPE"PLUMBING"
HDL_TAP"TRUE";
"B \NAC \NWC"7;
"S \NAC"
BN"5"48;
%"TAP"
"1","(-3700,4125)","0","mstr_standard","I389";
;
CDS_LIB"mstr_standard"
BODY_TYPE"PLUMBING"
HDL_TAP"TRUE";
"B \NAC \NWC"7;
"S \NAC"
BN"4"52;
%"TAP"
"1","(-3700,4025)","0","mstr_standard","I390";
;
CDS_LIB"mstr_standard"
BODY_TYPE"PLUMBING"
HDL_TAP"TRUE";
"B \NAC \NWC"7;
"S \NAC"
BN"3"56;
%"TAP"
"1","(-3700,3925)","0","mstr_standard","I391";
;
CDS_LIB"mstr_standard"
BODY_TYPE"PLUMBING"
HDL_TAP"TRUE";
"B \NAC \NWC"7;
"S \NAC"
BN"2"60;
%"TAP"
"1","(-3700,3825)","0","mstr_standard","I392";
;
CDS_LIB"mstr_standard"
BODY_TYPE"PLUMBING"
HDL_TAP"TRUE";
"B \NAC \NWC"7;
"S \NAC"
BN"1"37;
%"TAP"
"1","(-3500,3675)","0","mstr_standard","I393";
;
CDS_LIB"mstr_standard"
BODY_TYPE"PLUMBING"
HDL_TAP"TRUE";
"B \NAC \NWC"10;
"S \NAC"
BN"0"35;
%"TAP"
"1","(-3500,3525)","0","mstr_standard","I394";
;
CDS_LIB"mstr_standard"
BODY_TYPE"PLUMBING"
HDL_TAP"TRUE";
"B \NAC \NWC"8;
"S \NAC"
BN"9"33;
%"TAP"
"1","(-3500,3425)","0","mstr_standard","I395";
;
CDS_LIB"mstr_standard"
BODY_TYPE"PLUMBING"
HDL_TAP"TRUE";
"B \NAC \NWC"8;
"S \NAC"
BN"8"68;
%"TAP"
"1","(-3500,3325)","0","mstr_standard","I396";
;
CDS_LIB"mstr_standard"
BODY_TYPE"PLUMBING"
HDL_TAP"TRUE";
"B \NAC \NWC"8;
"S \NAC"
BN"7"41;
%"TAP"
"1","(-3700,3575)","0","mstr_standard","I397";
;
CDS_LIB"mstr_standard"
BODY_TYPE"PLUMBING"
HDL_TAP"TRUE";
"B \NAC \NWC"9;
"S \NAC"
BN"9"34;
%"TAP"
"1","(-3700,3725)","0","mstr_standard","I398";
;
CDS_LIB"mstr_standard"
BODY_TYPE"PLUMBING"
HDL_TAP"TRUE";
"B \NAC \NWC"7;
"S \NAC"
BN"0"66;
%"TAP"
"1","(-3700,3375)","0","mstr_standard","I399";
;
CDS_LIB"mstr_standard"
BODY_TYPE"PLUMBING"
HDL_TAP"TRUE";
"B \NAC \NWC"9;
"S \NAC"
BN"7"67;
%"TAP"
"1","(-3700,3475)","0","mstr_standard","I400";
;
CDS_LIB"mstr_standard"
BODY_TYPE"PLUMBING"
HDL_TAP"TRUE";
"B \NAC \NWC"9;
"S \NAC"
BN"8"32;
%"TAP"
"1","(-3700,3275)","0","mstr_standard","I401";
;
CDS_LIB"mstr_standard"
BODY_TYPE"PLUMBING"
HDL_TAP"TRUE";
"B \NAC \NWC"9;
"S \NAC"
BN"6"43;
%"TAP"
"1","(-3500,3225)","0","mstr_standard","I402";
;
CDS_LIB"mstr_standard"
BODY_TYPE"PLUMBING"
HDL_TAP"TRUE";
"B \NAC \NWC"8;
"S \NAC"
BN"6"44;
%"TAP"
"1","(-3500,3125)","0","mstr_standard","I403";
;
CDS_LIB"mstr_standard"
BODY_TYPE"PLUMBING"
HDL_TAP"TRUE";
"B \NAC \NWC"8;
"S \NAC"
BN"5"47;
%"TAP"
"1","(-3500,3025)","0","mstr_standard","I404";
;
CDS_LIB"mstr_standard"
BODY_TYPE"PLUMBING"
HDL_TAP"TRUE";
"B \NAC \NWC"8;
"S \NAC"
BN"4"51;
%"TAP"
"1","(-3500,2925)","0","mstr_standard","I405";
;
CDS_LIB"mstr_standard"
BODY_TYPE"PLUMBING"
HDL_TAP"TRUE";
"B \NAC \NWC"8;
"S \NAC"
BN"3"55;
%"TAP"
"1","(-3500,2825)","0","mstr_standard","I406";
;
CDS_LIB"mstr_standard"
BODY_TYPE"PLUMBING"
HDL_TAP"TRUE";
"B \NAC \NWC"8;
"S \NAC"
BN"2"59;
%"TAP"
"1","(-3500,2725)","0","mstr_standard","I407";
;
CDS_LIB"mstr_standard"
BODY_TYPE"PLUMBING"
HDL_TAP"TRUE";
"B \NAC \NWC"8;
"S \NAC"
BN"1"63;
%"TAP"
"1","(-3700,3175)","0","mstr_standard","I408";
;
CDS_LIB"mstr_standard"
BODY_TYPE"PLUMBING"
HDL_TAP"TRUE";
"B \NAC \NWC"9;
"S \NAC"
BN"5"46;
%"TAP"
"1","(-3700,3075)","0","mstr_standard","I409";
;
CDS_LIB"mstr_standard"
BODY_TYPE"PLUMBING"
HDL_TAP"TRUE";
"B \NAC \NWC"9;
"S \NAC"
BN"4"50;
%"TAP"
"1","(-3700,2875)","0","mstr_standard","I410";
;
CDS_LIB"mstr_standard"
BODY_TYPE"PLUMBING"
HDL_TAP"TRUE";
"B \NAC \NWC"9;
"S \NAC"
BN"2"58;
%"TAP"
"1","(-3700,2975)","0","mstr_standard","I411";
;
CDS_LIB"mstr_standard"
BODY_TYPE"PLUMBING"
HDL_TAP"TRUE";
"B \NAC \NWC"9;
"S \NAC"
BN"3"54;
%"TAP"
"1","(-3700,2775)","0","mstr_standard","I412";
;
CDS_LIB"mstr_standard"
BODY_TYPE"PLUMBING"
HDL_TAP"TRUE";
"B \NAC \NWC"9;
"S \NAC"
BN"1"62;
%"TAP"
"1","(-3500,2625)","0","mstr_standard","I413";
;
CDS_LIB"mstr_standard"
BODY_TYPE"PLUMBING"
HDL_TAP"TRUE";
"B \NAC \NWC"8;
"S \NAC"
BN"0"65;
%"TAP"
"1","(-3700,2675)","0","mstr_standard","I414";
;
CDS_LIB"mstr_standard"
BODY_TYPE"PLUMBING"
HDL_TAP"TRUE";
"B \NAC \NWC"9;
"S \NAC"
BN"0"64;
%"SCONN288_DDR506112002KQ"
"2","(-4650,3625)","0","pure_quanta","I415";
;
LOCATION"J19"
$SEC"2"
CDS_SEC"2"
VALUE"SCONN288_DDR506112002KQ"
PART_TYPE"SMLF"
MATERIAL"IO"
PART_NUMBER"DFHST8FS479"
CDS_LMAN_SYM_OUTLINE"-600,1150,600,-1150"
NEEDS_NO_SIZE"TRUE"
CDS_LIB"pure_quanta";
"DQS7_A_C||TDQS7_A_C \B"
$PN"178"70;
"DQS6_A_T||TDQS6_A_T"
$PN"168"69;
"DQS8_B_T||TDQS8_B_T"
$PN"283"32;
"DQS8_B_C||TDQS8_B_C \B"
$PN"282"68;
"DQS7_B_T||TDQS7_B_T"
$PN"272"67;
"DQS0_A_C \B"
$PN"12"35;
"DQS0_A_T"
$PN"11"66;
"DQS0_B_C \B"
$PN"105"65;
"DQS0_B_T"
$PN"104"64;
"DQS1_A_C \B"
$PN"23"36;
"DQS1_A_T"
$PN"22"37;
"DQS1_B_C \B"
$PN"116"63;
"DQS1_B_T"
$PN"115"62;
"DQS2_A_C \B"
$PN"34"61;
"DQS2_A_T"
$PN"33"60;
"DQS2_B_C \B"
$PN"127"59;
"DQS2_B_T"
$PN"126"58;
"DQS3_A_C \B"
$PN"45"57;
"DQS3_A_T"
$PN"44"56;
"DQS3_B_C \B"
$PN"138"55;
"DQS3_B_T"
$PN"137"54;
"DQS4_A_C \B"
$PN"56"53;
"DQS4_A_T"
$PN"55"52;
"DQS4_B_C \B"
$PN"238"51;
"DQS4_B_T"
$PN"239"50;
"DQS5_A_C||TDQS5_A_C||DQS5_A_T||TDQS5_A_T \B"
$PN"156"49;
"DQS5_A_T||TDQS5_A_T"
$PN"157"48;
"DQS5_B_C||TDQS5_B_C \B"
$PN"249"47;
"DQS5_B_T||TDQS5_B_T"
$PN"250"46;
"DQS6_A_C||TDQS6_A_C||DQS6_A_T||TDQS6_A_T \B"
$PN"167"45;
"DQS6_B_C||TDQS6_B_C \B"
$PN"260"44;
"DQS6_B_T||TDQS6_B_T"
$PN"261"43;
"DQS7_A_T||TDQS7_A_T"
$PN"179"42;
"DQS7_B_C||TDQS7_B_C \B"
$PN"271"41;
"DQS8_A_C||TDQS8_A_C \B"
$PN"189"40;
"DQS8_A_T||TDQS8_A_T"
$PN"190"39;
"DQS9_A_C||TDQS9_A_C \B"
$PN"200"31;
"DQS9_A_T||TDQS9_A_T"
$PN"201"38;
"DQS9_B_C||TDQS9_B_C \B"
$PN"94"33;
"DQS9_B_T||TDQS9_B_T||DBI4_B_N"
$PN"93"34;
%"GND"
"1","(-2950,5225)","0","pure_quanta_power","I416";
;
CDS_LIB"pure_quanta_power"
BOM_COST"MEM"
SIZE"1B"
ROOM"MEM_EFGH_DECOUPLING_CAPS"
HDL_POWER"GND";
"A<SIZE-1..0>\NAC"28;
%"Q_CAP"
"1","(-2950,5575)","2","pure_quanta","I417";
;
LOCATION"C149"
$SEC"1"
CDS_SEC"1"
VALUE"10UF"
VOLTAGE"25V"
PACK_TYPE"C0805"
MATERIAL"X6S"
PART_NUMBER"CH6104KEA00"
TOLERANCE"10%"
BOM_COST"MEM"
CDS_LIB"pure_quanta"
ROOM"MEM_CH_A_CPU0_DIMM1";
"B"
$PN"2"28;
"A"
$PN"1"30;
%"Q_CAP"
"1","(-2375,5575)","2","pure_quanta","I418";
;
LOCATION"C150"
$SEC"1"
CDS_SEC"1"
MATERIAL"X6S"
VALUE"10UF"
VOLTAGE"25V"
PACK_TYPE"C0805"
TOLERANCE"10%"
PART_NUMBER"CH6104KEA00"
BOM_COST"MEM"
CDS_LIB"pure_quanta"
ROOM"MEM_CH_A_CPU0_DIMM1";
"B"
$PN"2"28;
"A"
$PN"1"30;
%"UNIVERSAL_POWER"
"1","(-2950,5900)","0","pure_quanta_power","I419";
;
HDL_POWER"P12V_MEM_1"
BOM_COST"VR_SYSTEM"
CDS_LIB"pure_quanta_power";
"A"30;
%"Q_RES"
"1","(-7825,2850)","0","pure_quanta","I421";
;
$LOCATION"R1"
CDS_LOCATION"R1"
$SEC"1"
CDS_SEC"1"
VALUE"49.9"
CDS_LIB"pure_quanta"
PART_NUMBER"CS04992FB07"
TOLERANCE"1%"
WATTAGE"1/16W"
PACK_TYPE"0402LF"
MATERIAL"CHIP";
"B"
$PN"2"15;
"A"
$PN"1"14;
END.
